(kicad_pcb
	(version 20260206)
	(generator "pcbnew")
	(generator_version "10.0")
	(general
		(thickness 1.6)
		(legacy_teardrops no)
	)
	(paper "A4")
	(title_block
		(title "Bryce Canyon_SCC_16316-1_OCP.brd")
		(comment 1 "Bryce Canyon / footprints 346-353 of 1561")
	)
	(layers
		(0 "F.Cu" signal "TOP")
		(4 "In1.Cu" signal "L2GND")
		(6 "In2.Cu" signal "L3")
		(8 "In3.Cu" signal "L4VCC")
		(10 "In4.Cu" signal "L5VCC")
		(12 "In5.Cu" signal "L6")
		(14 "In6.Cu" signal "L7GND")
		(2 "B.Cu" signal "BOTTOM")
		(9 "F.Adhes" user "F.Adhesive")
		(11 "B.Adhes" user "B.Adhesive")
		(13 "F.Paste" user "Package Geometry/Pastemask Top")
		(15 "B.Paste" user "Package Geometry/Pastemask Bottom")
		(5 "F.SilkS" user "Ref Des/Silkscreen Top")
		(7 "B.SilkS" user "Ref Des/Silkscreen Bottom")
		(1 "F.Mask" user "Board Geometry/Soldermask Top")
		(3 "B.Mask" user "Board Geometry/Soldermask Bottom")
		(17 "Dwgs.User" user "User.Drawings")
		(19 "Cmts.User" user "User.Comments")
		(21 "Eco1.User" user "User.Eco1")
		(23 "Eco2.User" user "User.Eco2")
		(25 "Edge.Cuts" user "Board Geometry/Outline")
		(27 "Margin" user)
		(31 "F.CrtYd" user "Package Geometry/Place Bound Top")
		(29 "B.CrtYd" user "Package Geometry/Place Bound Bottom")
		(35 "F.Fab" user "Ref Des/Assembly Top")
		(33 "B.Fab" user "Ref Des/Assembly Bottom")
	)
	(footprint ""
		(layer "F.Cu")
		(at 19.177 -79.756 90)
		(property "Reference" "R341"
			(at 0 0 90)
			(layer "F.SilkS")
			(hide yes)
			(effects
				(font
					(size 1.27 1.27)
				)
			)
		)
		(property "Value" "0R2J-2-GP"
			(at 0.064008 -3.993896 90)
			(unlocked yes)
			(layer "F.Fab")
			(hide yes)
			(effects
				(font
					(size 1.016 1.016)
					(thickness 0.1524)
				)
			)
		)
		(property "Device Type" "R402H16"
			(at 0.064008 -5.517896 90)
			(unlocked yes)
			(layer "F.Fab")
			(hide yes)
			(effects
				(font
					(size 1.016 1.016)
					(thickness 0.1524)
				)
			)
		)
		(duplicate_pad_numbers_are_jumpers no)
		(fp_line
			(start 0.508 -0.9398)
			(end -0.508 -0.9398)
			(stroke
				(width 0.1524)
				(type default)
			)
			(layer "F.SilkS")
		)
		(fp_line
			(start -0.508 -0.9398)
			(end -0.508 0.9398)
			(stroke
				(width 0.1524)
				(type default)
			)
			(layer "F.SilkS")
		)
		(fp_rect
			(start -0.508 0.9398)
			(end 0.508 -0.9398)
			(stroke
				(width 0)
				(type default)
			)
			(fill no)
			(layer "F.CrtYd")
		)
		(fp_rect
			(start -0.508 0.9398)
			(end 0.508 -0.9398)
			(stroke
				(width 0)
				(type default)
			)
			(fill no)
			(layer "F.Fab")
		)
		(pad "1" smd custom
			(at 0 -0.4445 90)
			(size 0.1397 0.1397)
			(layers "F.Cu" "F.Mask" "F.Paste")
			(net "EXP_EEPROM_WP")
			(options
				(clearance outline)
				(anchor circle)
			)
			(primitives
				(gr_poly
					(pts
						(arc
							(start -0.1778 -0.2794)
							(mid -0.249642 -0.249642)
							(end -0.2794 -0.1778)
						)
						(arc
							(start -0.2794 0.1778)
							(mid -0.249642 0.249642)
							(end -0.1778 0.2794)
						)
						(arc
							(start 0.1778 0.2794)
							(mid 0.249642 0.249642)
							(end 0.2794 0.1778)
						)
						(arc
							(start 0.2794 -0.1778)
							(mid 0.249642 -0.249642)
							(end 0.1778 -0.2794)
						)
					)
					(width 0)
					(fill yes)
				)
			)
		)
		(pad "2" smd custom
			(at 0 0.4445 90)
			(size 0.1397 0.1397)
			(layers "F.Cu" "F.Mask" "F.Paste")
			(net "GND")
			(options
				(clearance outline)
				(anchor circle)
			)
			(primitives
				(gr_poly
					(pts
						(arc
							(start -0.1778 -0.2794)
							(mid -0.249642 -0.249642)
							(end -0.2794 -0.1778)
						)
						(arc
							(start -0.2794 0.1778)
							(mid -0.249642 0.249642)
							(end -0.1778 0.2794)
						)
						(arc
							(start 0.1778 0.2794)
							(mid 0.249642 0.249642)
							(end 0.2794 0.1778)
						)
						(arc
							(start 0.2794 -0.1778)
							(mid 0.249642 -0.249642)
							(end 0.1778 -0.2794)
						)
					)
					(width 0)
					(fill yes)
				)
			)
		)
	)
	(footprint ""
		(layer "F.Cu")
		(at 135.355076 -88.72601)
		(property "Reference" "R69"
			(at 0 0 0)
			(layer "F.SilkS")
			(hide yes)
			(effects
				(font
					(size 1.27 1.27)
				)
			)
		)
		(property "Value" "1KR2F-3-GP"
			(at 0.064008 -3.993896 0)
			(unlocked yes)
			(layer "F.Fab")
			(hide yes)
			(effects
				(font
					(size 1.016 1.016)
					(thickness 0.1524)
				)
			)
		)
		(property "Device Type" "R402H16"
			(at 0.064008 -5.517896 0)
			(unlocked yes)
			(layer "F.Fab")
			(hide yes)
			(effects
				(font
					(size 1.016 1.016)
					(thickness 0.1524)
				)
			)
		)
		(duplicate_pad_numbers_are_jumpers no)
		(fp_line
			(start -0.508 -0.9398)
			(end -0.508 0.9398)
			(stroke
				(width 0.1524)
				(type default)
			)
			(layer "F.SilkS")
		)
		(fp_line
			(start 0.508 -0.9398)
			(end -0.508 -0.9398)
			(stroke
				(width 0.1524)
				(type default)
			)
			(layer "F.SilkS")
		)
		(fp_rect
			(start -0.508 0.9398)
			(end 0.508 -0.9398)
			(stroke
				(width 0)
				(type default)
			)
			(fill no)
			(layer "F.CrtYd")
		)
		(fp_rect
			(start -0.508 0.9398)
			(end 0.508 -0.9398)
			(stroke
				(width 0)
				(type default)
			)
			(fill no)
			(layer "F.Fab")
		)
		(pad "1" smd custom
			(at 0 -0.4445)
			(size 0.1397 0.1397)
			(layers "F.Cu" "F.Mask" "F.Paste")
			(net "P1V8_E")
			(options
				(clearance outline)
				(anchor circle)
			)
			(primitives
				(gr_poly
					(pts
						(arc
							(start -0.1778 -0.2794)
							(mid -0.249642 -0.249642)
							(end -0.2794 -0.1778)
						)
						(arc
							(start -0.2794 0.1778)
							(mid -0.249642 0.249642)
							(end -0.1778 0.2794)
						)
						(arc
							(start 0.1778 0.2794)
							(mid 0.249642 0.249642)
							(end 0.2794 0.1778)
						)
						(arc
							(start 0.2794 -0.1778)
							(mid 0.249642 -0.249642)
							(end 0.1778 -0.2794)
						)
					)
					(width 0)
					(fill yes)
				)
			)
		)
		(pad "2" smd custom
			(at 0 0.4445)
			(size 0.1397 0.1397)
			(layers "F.Cu" "F.Mask" "F.Paste")
			(net "EXP_I2C_SDA10")
			(options
				(clearance outline)
				(anchor circle)
			)
			(primitives
				(gr_poly
					(pts
						(arc
							(start -0.1778 -0.2794)
							(mid -0.249642 -0.249642)
							(end -0.2794 -0.1778)
						)
						(arc
							(start -0.2794 0.1778)
							(mid -0.249642 0.249642)
							(end -0.1778 0.2794)
						)
						(arc
							(start 0.1778 0.2794)
							(mid 0.249642 0.249642)
							(end 0.2794 0.1778)
						)
						(arc
							(start 0.2794 -0.1778)
							(mid 0.249642 -0.249642)
							(end 0.1778 -0.2794)
						)
					)
					(width 0)
					(fill yes)
				)
			)
		)
	)
	(footprint ""
		(layer "F.Cu")
		(at 153.81478 -120.45442)
		(property "Reference" "G5"
			(at 0 0 0)
			(layer "F.SilkS")
			(hide yes)
			(effects
				(font
					(size 1.27 1.27)
				)
			)
		)
		(property "Value" "COPPER-CLOSE-GP-U"
			(at 0.0762 -2.8702 0)
			(unlocked yes)
			(layer "F.Fab")
			(hide yes)
			(effects
				(font
					(size 1.016 1.016)
					(thickness 0.1524)
				)
			)
		)
		(property "Device Type" "CON2C-U"
			(at 0.0762 -4.3942 0)
			(unlocked yes)
			(layer "F.Fab")
			(hide yes)
			(effects
				(font
					(size 1.016 1.016)
					(thickness 0.1524)
				)
			)
		)
		(duplicate_pad_numbers_are_jumpers no)
		(fp_rect
			(start -0.9398 0.9652)
			(end 0.9398 -0.9652)
			(stroke
				(width 0)
				(type default)
			)
			(fill no)
			(layer "F.CrtYd")
		)
		(fp_rect
			(start -0.9398 0.9652)
			(end 0.9398 -0.9652)
			(stroke
				(width 0)
				(type default)
			)
			(fill no)
			(layer "F.Fab")
		)
		(pad "1" smd custom
			(at 0 -0.5334)
			(size 0.17145 0.17145)
			(layers "F.Cu" "F.Mask" "F.Paste")
			(net "AGND_P1V5_E")
			(options
				(clearance outline)
				(anchor circle)
			)
			(primitives
				(gr_poly
					(pts
						(xy -0.127 0.3429) (xy -0.127 0.1651) (xy -0.635 -0.3429) (xy 0.635 -0.3429) (xy 0.127 0.1651)
						(xy 0.127 0.3429)
					)
					(width 0)
					(fill yes)
				)
			)
		)
		(pad "2" smd custom
			(at 0 0.5334)
			(size 0.17145 0.17145)
			(layers "F.Cu" "F.Mask" "F.Paste")
			(net "GND")
			(options
				(clearance outline)
				(anchor circle)
			)
			(primitives
				(gr_poly
					(pts
						(xy -0.635 0.3429) (xy -0.127 -0.1651) (xy -0.127 -0.3429) (xy 0.127 -0.3429) (xy 0.127 -0.1651)
						(xy 0.635 0.3429)
					)
					(width 0)
					(fill yes)
				)
			)
		)
	)
	(footprint ""
		(layer "F.Cu")
		(at 58.9788 -92.0496 -90)
		(property "Reference" "C595"
			(at 0 0 270)
			(layer "F.SilkS")
			(hide yes)
			(effects
				(font
					(size 1.27 1.27)
				)
			)
		)
		(property "Value" "SC10U16V5KX-7-GP-U"
			(at -0.0762 -6.1214 270)
			(unlocked yes)
			(layer "F.Fab")
			(hide yes)
			(effects
				(font
					(size 1.016 1.016)
					(thickness 0.1524)
				)
			)
		)
		(property "Device Type" "C805H58"
			(at -0.0762 -8.1534 270)
			(unlocked yes)
			(layer "F.Fab")
			(hide yes)
			(effects
				(font
					(size 1.016 1.016)
					(thickness 0.1524)
				)
			)
		)
		(duplicate_pad_numbers_are_jumpers no)
		(fp_line
			(start 0.635 0)
			(end -0.635 0)
			(stroke
				(width 0.508)
				(type default)
			)
			(layer "F.SilkS")
		)
		(fp_rect
			(start -0.9652 1.778)
			(end 0.9652 -1.778)
			(stroke
				(width 0)
				(type default)
			)
			(fill no)
			(layer "F.CrtYd")
		)
		(fp_poly
			(pts
				(xy -0.9652 -1.778) (xy 0.9652 -1.778) (xy 0.9652 1.778) (xy -0.9652 1.778)
			)
			(stroke
				(width 0)
				(type default)
			)
			(fill no)
			(layer "F.Fab")
		)
		(pad "1" smd rect
			(at 0 -0.9652 270)
			(size 1.397 1.143)
			(layers "F.Cu" "F.Mask" "F.Paste")
			(net "P12V_STBY_VIN_U10")
		)
		(pad "2" smd rect
			(at 0 0.9652 270)
			(size 1.397 1.143)
			(layers "F.Cu" "F.Mask" "F.Paste")
			(net "GND")
		)
	)
	(footprint ""
		(layer "F.Cu")
		(at 75.311 -35.941)
		(property "Reference" "C256"
			(at 0 0 0)
			(layer "F.SilkS")
			(hide yes)
			(effects
				(font
					(size 1.27 1.27)
				)
			)
		)
		(property "Value" "SC22U6D3V3MX-9-GP-U"
			(at 0 -2.8194 0)
			(unlocked yes)
			(layer "F.Fab")
			(hide yes)
			(effects
				(font
					(size 1.016 1.016)
					(thickness 0.1524)
				)
			)
		)
		(property "Device Type" "C603H40"
			(at 0 -4.3434 0)
			(unlocked yes)
			(layer "F.Fab")
			(hide yes)
			(effects
				(font
					(size 1.016 1.016)
					(thickness 0.1524)
				)
			)
		)
		(duplicate_pad_numbers_are_jumpers no)
		(fp_line
			(start 0.508 0)
			(end -0.508 0)
			(stroke
				(width 0.2032)
				(type default)
			)
			(layer "F.SilkS")
		)
		(fp_rect
			(start -0.5842 1.3335)
			(end 0.5842 -1.3335)
			(stroke
				(width 0)
				(type default)
			)
			(fill no)
			(layer "F.CrtYd")
		)
		(fp_rect
			(start -0.5842 1.3335)
			(end 0.5842 -1.3335)
			(stroke
				(width 0)
				(type default)
			)
			(fill no)
			(layer "F.Fab")
		)
		(pad "1" smd custom
			(at 0 -0.762)
			(size 0.2159 0.2159)
			(layers "F.Cu" "F.Mask" "F.Paste")
			(net "GB_VDDA")
			(options
				(clearance outline)
				(anchor circle)
			)
			(primitives
				(gr_poly
					(pts
						(arc
							(start -0.3302 -0.4318)
							(mid -0.402042 -0.402042)
							(end -0.4318 -0.3302)
						)
						(arc
							(start -0.4318 0.3302)
							(mid -0.402042 0.402042)
							(end -0.3302 0.4318)
						)
						(arc
							(start 0.3302 0.4318)
							(mid 0.402042 0.402042)
							(end 0.4318 0.3302)
						)
						(arc
							(start 0.4318 -0.3302)
							(mid 0.402042 -0.402042)
							(end 0.3302 -0.4318)
						)
					)
					(width 0)
					(fill yes)
				)
			)
		)
		(pad "2" smd custom
			(at 0 0.762)
			(size 0.2159 0.2159)
			(layers "F.Cu" "F.Mask" "F.Paste")
			(net "GND")
			(options
				(clearance outline)
				(anchor circle)
			)
			(primitives
				(gr_poly
					(pts
						(arc
							(start -0.3302 -0.4318)
							(mid -0.402042 -0.402042)
							(end -0.4318 -0.3302)
						)
						(arc
							(start -0.4318 0.3302)
							(mid -0.402042 0.402042)
							(end -0.3302 0.4318)
						)
						(arc
							(start 0.3302 0.4318)
							(mid 0.402042 0.402042)
							(end 0.4318 0.3302)
						)
						(arc
							(start 0.4318 -0.3302)
							(mid 0.402042 -0.402042)
							(end 0.3302 -0.4318)
						)
					)
					(width 0)
					(fill yes)
				)
			)
		)
	)
	(footprint ""
		(layer "F.Cu")
		(at 147.574 -100.457 180)
		(property "Reference" "C719"
			(at 0 0 180)
			(layer "F.SilkS")
			(hide yes)
			(effects
				(font
					(size 1.27 1.27)
				)
			)
		)
		(property "Value" "SC22U6D3V3MX-9-GP-U"
			(at 0 -2.8194 180)
			(unlocked yes)
			(layer "F.Fab")
			(hide yes)
			(effects
				(font
					(size 1.016 1.016)
					(thickness 0.1524)
				)
			)
		)
		(property "Device Type" "C603H40"
			(at 0 -4.3434 180)
			(unlocked yes)
			(layer "F.Fab")
			(hide yes)
			(effects
				(font
					(size 1.016 1.016)
					(thickness 0.1524)
				)
			)
		)
		(duplicate_pad_numbers_are_jumpers no)
		(fp_line
			(start 0.508 0)
			(end -0.508 0)
			(stroke
				(width 0.2032)
				(type default)
			)
			(layer "F.SilkS")
		)
		(fp_rect
			(start -0.5842 1.3335)
			(end 0.5842 -1.3335)
			(stroke
				(width 0)
				(type default)
			)
			(fill no)
			(layer "F.CrtYd")
		)
		(fp_rect
			(start -0.5842 1.3335)
			(end 0.5842 -1.3335)
			(stroke
				(width 0)
				(type default)
			)
			(fill no)
			(layer "F.Fab")
		)
		(pad "1" smd custom
			(at 0 -0.762 180)
			(size 0.2159 0.2159)
			(layers "F.Cu" "F.Mask" "F.Paste")
			(net "GB_VDDH")
			(options
				(clearance outline)
				(anchor circle)
			)
			(primitives
				(gr_poly
					(pts
						(arc
							(start -0.3302 -0.4318)
							(mid -0.402042 -0.402042)
							(end -0.4318 -0.3302)
						)
						(arc
							(start -0.4318 0.3302)
							(mid -0.402042 0.402042)
							(end -0.3302 0.4318)
						)
						(arc
							(start 0.3302 0.4318)
							(mid 0.402042 0.402042)
							(end 0.4318 0.3302)
						)
						(arc
							(start 0.4318 -0.3302)
							(mid 0.402042 -0.402042)
							(end 0.3302 -0.4318)
						)
					)
					(width 0)
					(fill yes)
				)
			)
		)
		(pad "2" smd custom
			(at 0 0.762 180)
			(size 0.2159 0.2159)
			(layers "F.Cu" "F.Mask" "F.Paste")
			(net "GND")
			(options
				(clearance outline)
				(anchor circle)
			)
			(primitives
				(gr_poly
					(pts
						(arc
							(start -0.3302 -0.4318)
							(mid -0.402042 -0.402042)
							(end -0.4318 -0.3302)
						)
						(arc
							(start -0.4318 0.3302)
							(mid -0.402042 0.402042)
							(end -0.3302 0.4318)
						)
						(arc
							(start 0.3302 0.4318)
							(mid 0.402042 0.402042)
							(end 0.4318 0.3302)
						)
						(arc
							(start 0.4318 -0.3302)
							(mid 0.402042 -0.402042)
							(end 0.3302 -0.4318)
						)
					)
					(width 0)
					(fill yes)
				)
			)
		)
	)
	(footprint ""
		(layer "F.Cu")
		(at 145.37055 -32.408114 102)
		(property "Reference" "C328"
			(at 0 0 102)
			(layer "F.SilkS")
			(hide yes)
			(effects
				(font
					(size 1.27 1.27)
				)
			)
		)
		(property "Value" "SCD01U16V1KX-GP"
			(at -2.831995 -1.740026 102)
			(unlocked yes)
			(layer "F.Fab")
			(hide yes)
			(effects
				(font
					(size 1.016 1.016)
					(thickness 0.1524)
				)
			)
		)
		(property "Device Type" "C0201H13"
			(at -2.831925 -3.263781 102)
			(unlocked yes)
			(layer "F.Fab")
			(hide yes)
			(effects
				(font
					(size 1.016 1.016)
					(thickness 0.1524)
				)
			)
		)
		(duplicate_pad_numbers_are_jumpers no)
		(fp_poly
			(pts
				(xy -0.279454 -0.647706) (xy 0.279346 -0.647706) (xy 0.279346 0.647694) (xy -0.279454 0.647694)
			)
			(stroke
				(width 0)
				(type default)
			)
			(fill no)
			(layer "F.CrtYd")
		)
		(fp_poly
			(pts
				(xy -0.279454 -0.647706) (xy 0.279346 -0.647706) (xy 0.279346 0.647694) (xy -0.279454 0.647694)
			)
			(stroke
				(width 0)
				(type default)
			)
			(fill no)
			(layer "F.Fab")
		)
		(pad "1" smd custom
			(at -0.000001 -0.2794 102)
			(size 0.0762 0.0762)
			(layers "F.Cu" "F.Mask" "F.Paste")
			(net "PHY_SCC_TO_IOC_40_DN")
			(options
				(clearance outline)
				(anchor circle)
			)
			(primitives
				(gr_poly
					(pts
						(arc
							(start 0.1524 -0.127)
							(mid 0.137521 -0.162921)
							(end 0.1016 -0.1778)
						)
						(arc
							(start -0.1016 -0.1778)
							(mid -0.137521 -0.162921)
							(end -0.1524 -0.127)
						)
						(arc
							(start -0.1524 0.127)
							(mid -0.137521 0.162921)
							(end -0.1016 0.1778)
						)
						(arc
							(start 0.1016 0.1778)
							(mid 0.137521 0.162921)
							(end 0.1524 0.127)
						)
					)
					(width 0)
					(fill yes)
				)
			)
		)
		(pad "2" smd custom
			(at 0.000001 0.2794 102)
			(size 0.0762 0.0762)
			(layers "F.Cu" "F.Mask" "F.Paste")
			(net "PHY_SCC_TO_IOC_C_40_DN")
			(options
				(clearance outline)
				(anchor circle)
			)
			(primitives
				(gr_poly
					(pts
						(arc
							(start 0.1524 -0.127)
							(mid 0.137521 -0.162921)
							(end 0.1016 -0.1778)
						)
						(arc
							(start -0.1016 -0.1778)
							(mid -0.137521 -0.162921)
							(end -0.1524 -0.127)
						)
						(arc
							(start -0.1524 0.127)
							(mid -0.137521 0.162921)
							(end -0.1016 0.1778)
						)
						(arc
							(start 0.1016 0.1778)
							(mid 0.137521 0.162921)
							(end 0.1524 0.127)
						)
					)
					(width 0)
					(fill yes)
				)
			)
		)
	)
	(footprint ""
		(layer "F.Cu")
		(at 169.489882 -88.142572 -90)
		(property "Reference" "C744"
			(at 0 0 270)
			(layer "F.SilkS")
			(hide yes)
			(effects
				(font
					(size 1.27 1.27)
				)
			)
		)
		(property "Value" "SC2200P50V2KX-2GP"
			(at 1.1811 -2.7051 270)
			(unlocked yes)
			(layer "F.Fab")
			(hide yes)
			(effects
				(font
					(size 1.016 1.016)
					(thickness 0.1524)
				)
			)
		)
		(property "Device Type" "C402H22"
			(at 1.1811 -4.2291 270)
			(unlocked yes)
			(layer "F.Fab")
			(hide yes)
			(effects
				(font
					(size 1.016 1.016)
					(thickness 0.1524)
				)
			)
		)
		(duplicate_pad_numbers_are_jumpers no)
		(fp_rect
			(start -0.4318 0.9525)
			(end 0.4318 -0.9525)
			(stroke
				(width 0)
				(type default)
			)
			(fill no)
			(layer "F.CrtYd")
		)
		(fp_rect
			(start -0.4318 0.9525)
			(end 0.4318 -0.9525)
			(stroke
				(width 0)
				(type default)
			)
			(fill no)
			(layer "F.Fab")
		)
		(pad "1" smd custom
			(at 0 -0.4445 270)
			(size 0.1524 0.1524)
			(layers "F.Cu" "F.Mask" "F.Paste")
			(net "VT235_VX_R")
			(options
				(clearance outline)
				(anchor circle)
			)
			(primitives
				(gr_poly
					(pts
						(arc
							(start 0.3048 -0.2032)
							(mid 0.275042 -0.275042)
							(end 0.2032 -0.3048)
						)
						(arc
							(start -0.2032 -0.3048)
							(mid -0.275042 -0.275042)
							(end -0.3048 -0.2032)
						)
						(arc
							(start -0.3048 0.2032)
							(mid -0.275042 0.275042)
							(end -0.2032 0.3048)
						)
						(arc
							(start 0.2032 0.3048)
							(mid 0.275042 0.275042)
							(end 0.3048 0.2032)
						)
					)
					(width 0)
					(fill yes)
				)
			)
		)
		(pad "2" smd custom
			(at 0 0.4445 270)
			(size 0.1524 0.1524)
			(layers "F.Cu" "F.Mask" "F.Paste")
			(net "GND")
			(options
				(clearance outline)
				(anchor circle)
			)
			(primitives
				(gr_poly
					(pts
						(arc
							(start 0.3048 -0.2032)
							(mid 0.275042 -0.275042)
							(end 0.2032 -0.3048)
						)
						(arc
							(start -0.2032 -0.3048)
							(mid -0.275042 -0.275042)
							(end -0.3048 -0.2032)
						)
						(arc
							(start -0.3048 0.2032)
							(mid -0.275042 0.275042)
							(end -0.2032 0.3048)
						)
						(arc
							(start 0.2032 0.3048)
							(mid 0.275042 0.275042)
							(end 0.3048 0.2032)
						)
					)
					(width 0)
					(fill yes)
				)
			)
		)
	)
)
